(kicad_pcb
	(version 20260206)
	(generator "pcbnew")
	(generator_version "10.0")
	(general
		(thickness 1.6)
		(legacy_teardrops no)
	)
	(paper "A4")
	(title_block
		(title "03242023_DA0F0TMBIJ0_F0T_Motherboard_J_brd_V01_OCP.brd")
		(comment 1 "Grand Teton / footprints 6057-6062 of 6105")
	)
	(layers
		(0 "F.Cu" signal "TOP")
		(4 "In1.Cu" signal "GND")
		(6 "In2.Cu" signal "IN1")
		(8 "In3.Cu" signal "GND1")
		(10 "In4.Cu" signal "IN2")
		(12 "In5.Cu" signal "GND2")
		(14 "In6.Cu" signal "IN3")
		(16 "In7.Cu" signal "GND3")
		(18 "In8.Cu" signal "VCC")
		(20 "In9.Cu" signal "VCC1")
		(22 "In10.Cu" signal "GND4")
		(24 "In11.Cu" signal "IN4")
		(26 "In12.Cu" signal "GND5")
		(28 "In13.Cu" signal "IN5")
		(30 "In14.Cu" signal "GND6")
		(32 "In15.Cu" signal "IN6")
		(34 "In16.Cu" signal "GND7")
		(2 "B.Cu" signal "BOTTOM")
		(9 "F.Adhes" user "F.Adhesive")
		(11 "B.Adhes" user "B.Adhesive")
		(13 "F.Paste" user "Package Geometry/Pastemask Top")
		(15 "B.Paste" user "Package Geometry/Pastemask Bottom")
		(5 "F.SilkS" user "Ref Des/Silkscreen Top")
		(7 "B.SilkS" user "Ref Des/Silkscreen Bottom")
		(1 "F.Mask" user "Board Geometry/Soldermask Top")
		(3 "B.Mask" user "Board Geometry/Soldermask Bottom")
		(17 "Dwgs.User" user "User.Drawings")
		(19 "Cmts.User" user "User.Comments")
		(21 "Eco1.User" user "User.Eco1")
		(23 "Eco2.User" user "User.Eco2")
		(25 "Edge.Cuts" user "Board Geometry/Outline")
		(27 "Margin" user)
		(31 "F.CrtYd" user "Package Geometry/Place Bound Top")
		(29 "B.CrtYd" user "Package Geometry/Place Bound Bottom")
		(35 "F.Fab" user "Ref Des/Assembly Top")
		(33 "B.Fab" user "Ref Des/Assembly Bottom")
	)
	(footprint ""
		(layer "B.Cu")
		(at 175.174402 -103.098346 90)
		(property "Reference" "R160"
			(at 0 0 90)
			(layer "B.SilkS")
			(hide yes)
			(effects
				(font
					(size 1.27 1.27)
				)
				(justify mirror)
			)
		)
		(property "Value" ""
			(at 0 0 90)
			(layer "B.Fab")
			(effects
				(font
					(size 1.27 1.27)
				)
				(justify mirror)
			)
		)
		(duplicate_pad_numbers_are_jumpers no)
		(fp_line
			(start 0.7874 -0.4064)
			(end -0.7874 -0.4064)
			(stroke
				(width 0.1524)
				(type default)
			)
			(layer "B.SilkS")
		)
		(fp_line
			(start -0.7874 -0.4064)
			(end -0.7874 0.4064)
			(stroke
				(width 0.1524)
				(type default)
			)
			(layer "B.SilkS")
		)
		(fp_line
			(start 0.7874 0.4064)
			(end 0.7874 -0.4064)
			(stroke
				(width 0.1524)
				(type default)
			)
			(layer "B.SilkS")
		)
		(fp_line
			(start -0.7874 0.4064)
			(end 0.7874 0.4064)
			(stroke
				(width 0.1524)
				(type default)
			)
			(layer "B.SilkS")
		)
		(fp_line
			(start 0.67945 -0.305054)
			(end 0.12065 -0.305054)
			(stroke
				(width 0.1)
				(type default)
			)
			(layer "B.Fab")
		)
		(fp_line
			(start 0.12065 -0.305054)
			(end 0.12065 -0.2794)
			(stroke
				(width 0.1)
				(type default)
			)
			(layer "B.Fab")
		)
		(fp_line
			(start -0.12065 -0.3048)
			(end -0.67945 -0.3048)
			(stroke
				(width 0.1)
				(type default)
			)
			(layer "B.Fab")
		)
		(fp_line
			(start -0.67945 -0.3048)
			(end -0.67945 0.3048)
			(stroke
				(width 0.1)
				(type default)
			)
			(layer "B.Fab")
		)
		(fp_line
			(start 0.12065 -0.2794)
			(end -0.12065 -0.2794)
			(stroke
				(width 0.1)
				(type default)
			)
			(layer "B.Fab")
		)
		(fp_line
			(start -0.12065 -0.2794)
			(end -0.12065 -0.3048)
			(stroke
				(width 0.1)
				(type default)
			)
			(layer "B.Fab")
		)
		(fp_line
			(start 0.12065 0.2794)
			(end 0.12065 0.3048)
			(stroke
				(width 0.1)
				(type default)
			)
			(layer "B.Fab")
		)
		(fp_line
			(start -0.120396 0.2794)
			(end 0.12065 0.2794)
			(stroke
				(width 0.1)
				(type default)
			)
			(layer "B.Fab")
		)
		(fp_line
			(start 0.67945 0.3048)
			(end 0.67945 -0.305054)
			(stroke
				(width 0.1)
				(type default)
			)
			(layer "B.Fab")
		)
		(fp_line
			(start 0.12065 0.3048)
			(end 0.67945 0.3048)
			(stroke
				(width 0.1)
				(type default)
			)
			(layer "B.Fab")
		)
		(fp_line
			(start -0.120396 0.3048)
			(end -0.120396 0.2794)
			(stroke
				(width 0.1)
				(type default)
			)
			(layer "B.Fab")
		)
		(fp_line
			(start -0.67945 0.3048)
			(end -0.120396 0.3048)
			(stroke
				(width 0.1)
				(type default)
			)
			(layer "B.Fab")
		)
		(pad "1" smd circle
			(at 0.40005 0 270)
			(size 0 0)
			(layers "B.Cu" "B.Mask" "B.Paste")
			(net "PWRGD_DRAMPWRGD_CPU0_AB_R_LVC1")
		)
		(pad "2" smd circle
			(at -0.40005 0 270)
			(size 0 0)
			(layers "B.Cu" "B.Mask" "B.Paste")
			(net "PWRGD_DRAMPWRGD_CPU0_AB_LVC1_R2")
		)
	)
	(footprint ""
		(layer "B.Cu")
		(at 111.310166 -212.049868)
		(property "Reference" "C463"
			(at 0 0 0)
			(layer "B.SilkS")
			(hide yes)
			(effects
				(font
					(size 1.27 1.27)
				)
				(justify mirror)
			)
		)
		(property "Value" ""
			(at 0 0 0)
			(layer "B.Fab")
			(effects
				(font
					(size 1.27 1.27)
				)
				(justify mirror)
			)
		)
		(duplicate_pad_numbers_are_jumpers no)
		(fp_line
			(start -1.524 -0.762)
			(end -1.524 0.762)
			(stroke
				(width 0.1524)
				(type default)
			)
			(layer "B.SilkS")
		)
		(fp_line
			(start -1.524 0.762)
			(end 1.524 0.762)
			(stroke
				(width 0.1524)
				(type default)
			)
			(layer "B.SilkS")
		)
		(fp_line
			(start 1.524 -0.762)
			(end -1.524 -0.762)
			(stroke
				(width 0.1524)
				(type default)
			)
			(layer "B.SilkS")
		)
		(fp_line
			(start 1.524 0.762)
			(end 1.524 -0.762)
			(stroke
				(width 0.1524)
				(type default)
			)
			(layer "B.SilkS")
		)
		(fp_line
			(start -1.1049 -0.724916)
			(end 1.1049 -0.724916)
			(stroke
				(width 0.1)
				(type default)
			)
			(layer "B.Fab")
		)
		(fp_line
			(start -1.1049 0.724916)
			(end -1.1049 -0.724916)
			(stroke
				(width 0.1)
				(type default)
			)
			(layer "B.Fab")
		)
		(fp_line
			(start 1.1049 -0.724916)
			(end 1.1049 0.724916)
			(stroke
				(width 0.1)
				(type default)
			)
			(layer "B.Fab")
		)
		(fp_line
			(start 1.1049 0.724916)
			(end -1.1049 0.724916)
			(stroke
				(width 0.1)
				(type default)
			)
			(layer "B.Fab")
		)
		(pad "1" smd rect
			(at 0.889 0)
			(size 1.016 1.27)
			(layers "B.Cu" "B.Mask" "B.Paste")
			(net "PVCCD_HV_CPU1")
		)
		(pad "2" smd rect
			(at -0.889 0)
			(size 1.016 1.27)
			(layers "B.Cu" "B.Mask" "B.Paste")
			(net "GND")
		)
	)
	(footprint ""
		(layer "B.Cu")
		(at 10.558272 -183.482996)
		(property "Reference" "R968"
			(at 0 0 0)
			(layer "B.SilkS")
			(hide yes)
			(effects
				(font
					(size 1.27 1.27)
				)
				(justify mirror)
			)
		)
		(property "Value" ""
			(at 0 0 0)
			(layer "B.Fab")
			(effects
				(font
					(size 1.27 1.27)
				)
				(justify mirror)
			)
		)
		(duplicate_pad_numbers_are_jumpers no)
		(fp_line
			(start -0.7874 -0.4064)
			(end -0.7874 0.4064)
			(stroke
				(width 0.1524)
				(type default)
			)
			(layer "B.SilkS")
		)
		(fp_line
			(start -0.7874 0.4064)
			(end 0.7874 0.4064)
			(stroke
				(width 0.1524)
				(type default)
			)
			(layer "B.SilkS")
		)
		(fp_line
			(start 0.7874 -0.4064)
			(end -0.7874 -0.4064)
			(stroke
				(width 0.1524)
				(type default)
			)
			(layer "B.SilkS")
		)
		(fp_line
			(start 0.7874 0.4064)
			(end 0.7874 -0.4064)
			(stroke
				(width 0.1524)
				(type default)
			)
			(layer "B.SilkS")
		)
		(fp_line
			(start -0.67945 -0.3048)
			(end -0.67945 0.3048)
			(stroke
				(width 0.1)
				(type default)
			)
			(layer "B.Fab")
		)
		(fp_line
			(start -0.67945 0.3048)
			(end -0.120396 0.3048)
			(stroke
				(width 0.1)
				(type default)
			)
			(layer "B.Fab")
		)
		(fp_line
			(start -0.12065 -0.3048)
			(end -0.67945 -0.3048)
			(stroke
				(width 0.1)
				(type default)
			)
			(layer "B.Fab")
		)
		(fp_line
			(start -0.12065 -0.2794)
			(end -0.12065 -0.3048)
			(stroke
				(width 0.1)
				(type default)
			)
			(layer "B.Fab")
		)
		(fp_line
			(start -0.120396 0.2794)
			(end 0.12065 0.2794)
			(stroke
				(width 0.1)
				(type default)
			)
			(layer "B.Fab")
		)
		(fp_line
			(start -0.120396 0.3048)
			(end -0.120396 0.2794)
			(stroke
				(width 0.1)
				(type default)
			)
			(layer "B.Fab")
		)
		(fp_line
			(start 0.12065 -0.305054)
			(end 0.12065 -0.2794)
			(stroke
				(width 0.1)
				(type default)
			)
			(layer "B.Fab")
		)
		(fp_line
			(start 0.12065 -0.2794)
			(end -0.12065 -0.2794)
			(stroke
				(width 0.1)
				(type default)
			)
			(layer "B.Fab")
		)
		(fp_line
			(start 0.12065 0.2794)
			(end 0.12065 0.3048)
			(stroke
				(width 0.1)
				(type default)
			)
			(layer "B.Fab")
		)
		(fp_line
			(start 0.12065 0.3048)
			(end 0.67945 0.3048)
			(stroke
				(width 0.1)
				(type default)
			)
			(layer "B.Fab")
		)
		(fp_line
			(start 0.67945 -0.305054)
			(end 0.12065 -0.305054)
			(stroke
				(width 0.1)
				(type default)
			)
			(layer "B.Fab")
		)
		(fp_line
			(start 0.67945 0.3048)
			(end 0.67945 -0.305054)
			(stroke
				(width 0.1)
				(type default)
			)
			(layer "B.Fab")
		)
		(pad "1" smd circle
			(at 0.40005 0 180)
			(size 0 0)
			(layers "B.Cu" "B.Mask" "B.Paste")
			(net "P3V3_AUX")
		)
		(pad "2" smd circle
			(at -0.40005 0 180)
			(size 0 0)
			(layers "B.Cu" "B.Mask" "B.Paste")
			(net "SMB_PEHPCPU1_LVC3_SDA")
		)
	)
	(footprint ""
		(layer "B.Cu")
		(at 351.26803 -359.103168 180)
		(property "Reference" "R2373"
			(at 0 0 0)
			(layer "B.SilkS")
			(hide yes)
			(effects
				(font
					(size 1.27 1.27)
				)
				(justify mirror)
			)
		)
		(property "Value" ""
			(at 0 0 0)
			(layer "B.Fab")
			(effects
				(font
					(size 1.27 1.27)
				)
				(justify mirror)
			)
		)
		(duplicate_pad_numbers_are_jumpers no)
		(fp_line
			(start 0.7874 0.4064)
			(end 0.7874 -0.4064)
			(stroke
				(width 0.1524)
				(type default)
			)
			(layer "B.SilkS")
		)
		(fp_line
			(start 0.7874 -0.4064)
			(end -0.7874 -0.4064)
			(stroke
				(width 0.1524)
				(type default)
			)
			(layer "B.SilkS")
		)
		(fp_line
			(start -0.7874 0.4064)
			(end 0.7874 0.4064)
			(stroke
				(width 0.1524)
				(type default)
			)
			(layer "B.SilkS")
		)
		(fp_line
			(start -0.7874 -0.4064)
			(end -0.7874 0.4064)
			(stroke
				(width 0.1524)
				(type default)
			)
			(layer "B.SilkS")
		)
		(fp_line
			(start 0.67945 0.3048)
			(end 0.67945 -0.305054)
			(stroke
				(width 0.1)
				(type default)
			)
			(layer "B.Fab")
		)
		(fp_line
			(start 0.67945 -0.305054)
			(end 0.12065 -0.305054)
			(stroke
				(width 0.1)
				(type default)
			)
			(layer "B.Fab")
		)
		(fp_line
			(start 0.12065 0.3048)
			(end 0.67945 0.3048)
			(stroke
				(width 0.1)
				(type default)
			)
			(layer "B.Fab")
		)
		(fp_line
			(start 0.12065 0.2794)
			(end 0.12065 0.3048)
			(stroke
				(width 0.1)
				(type default)
			)
			(layer "B.Fab")
		)
		(fp_line
			(start 0.12065 -0.2794)
			(end -0.12065 -0.2794)
			(stroke
				(width 0.1)
				(type default)
			)
			(layer "B.Fab")
		)
		(fp_line
			(start 0.12065 -0.305054)
			(end 0.12065 -0.2794)
			(stroke
				(width 0.1)
				(type default)
			)
			(layer "B.Fab")
		)
		(fp_line
			(start -0.120396 0.3048)
			(end -0.120396 0.2794)
			(stroke
				(width 0.1)
				(type default)
			)
			(layer "B.Fab")
		)
		(fp_line
			(start -0.120396 0.2794)
			(end 0.12065 0.2794)
			(stroke
				(width 0.1)
				(type default)
			)
			(layer "B.Fab")
		)
		(fp_line
			(start -0.12065 -0.2794)
			(end -0.12065 -0.3048)
			(stroke
				(width 0.1)
				(type default)
			)
			(layer "B.Fab")
		)
		(fp_line
			(start -0.12065 -0.3048)
			(end -0.67945 -0.3048)
			(stroke
				(width 0.1)
				(type default)
			)
			(layer "B.Fab")
		)
		(fp_line
			(start -0.67945 0.3048)
			(end -0.120396 0.3048)
			(stroke
				(width 0.1)
				(type default)
			)
			(layer "B.Fab")
		)
		(fp_line
			(start -0.67945 -0.3048)
			(end -0.67945 0.3048)
			(stroke
				(width 0.1)
				(type default)
			)
			(layer "B.Fab")
		)
		(pad "1" smd circle
			(at 0.40005 0)
			(size 0 0)
			(layers "B.Cu" "B.Mask" "B.Paste")
			(net "P3V3_AUX")
		)
		(pad "2" smd circle
			(at -0.40005 0)
			(size 0 0)
			(layers "B.Cu" "B.Mask" "B.Paste")
			(net "IRQ_PVCCIN_CPU0_VRHOT_R_N")
		)
	)
	(footprint ""
		(layer "B.Cu")
		(at 77.142594 -45.028866)
		(property "Reference" "R3571"
			(at 0 0 0)
			(layer "B.SilkS")
			(hide yes)
			(effects
				(font
					(size 1.27 1.27)
				)
				(justify mirror)
			)
		)
		(property "Value" ""
			(at 0 0 0)
			(layer "B.Fab")
			(effects
				(font
					(size 1.27 1.27)
				)
				(justify mirror)
			)
		)
		(duplicate_pad_numbers_are_jumpers no)
		(fp_line
			(start -0.7874 -0.4064)
			(end -0.7874 0.4064)
			(stroke
				(width 0.1524)
				(type default)
			)
			(layer "B.SilkS")
		)
		(fp_line
			(start -0.7874 0.4064)
			(end 0.7874 0.4064)
			(stroke
				(width 0.1524)
				(type default)
			)
			(layer "B.SilkS")
		)
		(fp_line
			(start 0.7874 -0.4064)
			(end -0.7874 -0.4064)
			(stroke
				(width 0.1524)
				(type default)
			)
			(layer "B.SilkS")
		)
		(fp_line
			(start 0.7874 0.4064)
			(end 0.7874 -0.4064)
			(stroke
				(width 0.1524)
				(type default)
			)
			(layer "B.SilkS")
		)
		(fp_line
			(start -0.67945 -0.3048)
			(end -0.67945 0.3048)
			(stroke
				(width 0.1)
				(type default)
			)
			(layer "B.Fab")
		)
		(fp_line
			(start -0.67945 0.3048)
			(end -0.120396 0.3048)
			(stroke
				(width 0.1)
				(type default)
			)
			(layer "B.Fab")
		)
		(fp_line
			(start -0.12065 -0.3048)
			(end -0.67945 -0.3048)
			(stroke
				(width 0.1)
				(type default)
			)
			(layer "B.Fab")
		)
		(fp_line
			(start -0.12065 -0.2794)
			(end -0.12065 -0.3048)
			(stroke
				(width 0.1)
				(type default)
			)
			(layer "B.Fab")
		)
		(fp_line
			(start -0.120396 0.2794)
			(end 0.12065 0.2794)
			(stroke
				(width 0.1)
				(type default)
			)
			(layer "B.Fab")
		)
		(fp_line
			(start -0.120396 0.3048)
			(end -0.120396 0.2794)
			(stroke
				(width 0.1)
				(type default)
			)
			(layer "B.Fab")
		)
		(fp_line
			(start 0.12065 -0.305054)
			(end 0.12065 -0.2794)
			(stroke
				(width 0.1)
				(type default)
			)
			(layer "B.Fab")
		)
		(fp_line
			(start 0.12065 -0.2794)
			(end -0.12065 -0.2794)
			(stroke
				(width 0.1)
				(type default)
			)
			(layer "B.Fab")
		)
		(fp_line
			(start 0.12065 0.2794)
			(end 0.12065 0.3048)
			(stroke
				(width 0.1)
				(type default)
			)
			(layer "B.Fab")
		)
		(fp_line
			(start 0.12065 0.3048)
			(end 0.67945 0.3048)
			(stroke
				(width 0.1)
				(type default)
			)
			(layer "B.Fab")
		)
		(fp_line
			(start 0.67945 -0.305054)
			(end 0.12065 -0.305054)
			(stroke
				(width 0.1)
				(type default)
			)
			(layer "B.Fab")
		)
		(fp_line
			(start 0.67945 0.3048)
			(end 0.67945 -0.305054)
			(stroke
				(width 0.1)
				(type default)
			)
			(layer "B.Fab")
		)
		(pad "1" smd circle
			(at 0.40005 0 180)
			(size 0 0)
			(layers "B.Cu" "B.Mask" "B.Paste")
			(net "P3V3_OCP_V3_2")
		)
		(pad "2" smd circle
			(at -0.40005 0 180)
			(size 0 0)
			(layers "B.Cu" "B.Mask" "B.Paste")
			(net "VSENSE_P12V_INA230_3_INN")
		)
	)
	(footprint ""
		(layer "B.Cu")
		(at 297.942 -259.171948 180)
		(property "Reference" "R186"
			(at 0 0 0)
			(layer "B.SilkS")
			(hide yes)
			(effects
				(font
					(size 1.27 1.27)
				)
				(justify mirror)
			)
		)
		(property "Value" ""
			(at 0 0 0)
			(layer "B.Fab")
			(effects
				(font
					(size 1.27 1.27)
				)
				(justify mirror)
			)
		)
		(duplicate_pad_numbers_are_jumpers no)
		(fp_line
			(start 0.7874 0.4064)
			(end 0.7874 -0.4064)
			(stroke
				(width 0.1524)
				(type default)
			)
			(layer "B.SilkS")
		)
		(fp_line
			(start 0.7874 -0.4064)
			(end -0.7874 -0.4064)
			(stroke
				(width 0.1524)
				(type default)
			)
			(layer "B.SilkS")
		)
		(fp_line
			(start -0.7874 0.4064)
			(end 0.7874 0.4064)
			(stroke
				(width 0.1524)
				(type default)
			)
			(layer "B.SilkS")
		)
		(fp_line
			(start -0.7874 -0.4064)
			(end -0.7874 0.4064)
			(stroke
				(width 0.1524)
				(type default)
			)
			(layer "B.SilkS")
		)
		(fp_line
			(start 0.67945 0.3048)
			(end 0.67945 -0.305054)
			(stroke
				(width 0.1)
				(type default)
			)
			(layer "B.Fab")
		)
		(fp_line
			(start 0.67945 -0.305054)
			(end 0.12065 -0.305054)
			(stroke
				(width 0.1)
				(type default)
			)
			(layer "B.Fab")
		)
		(fp_line
			(start 0.12065 0.3048)
			(end 0.67945 0.3048)
			(stroke
				(width 0.1)
				(type default)
			)
			(layer "B.Fab")
		)
		(fp_line
			(start 0.12065 0.2794)
			(end 0.12065 0.3048)
			(stroke
				(width 0.1)
				(type default)
			)
			(layer "B.Fab")
		)
		(fp_line
			(start 0.12065 -0.2794)
			(end -0.12065 -0.2794)
			(stroke
				(width 0.1)
				(type default)
			)
			(layer "B.Fab")
		)
		(fp_line
			(start 0.12065 -0.305054)
			(end 0.12065 -0.2794)
			(stroke
				(width 0.1)
				(type default)
			)
			(layer "B.Fab")
		)
		(fp_line
			(start -0.120396 0.3048)
			(end -0.120396 0.2794)
			(stroke
				(width 0.1)
				(type default)
			)
			(layer "B.Fab")
		)
		(fp_line
			(start -0.120396 0.2794)
			(end 0.12065 0.2794)
			(stroke
				(width 0.1)
				(type default)
			)
			(layer "B.Fab")
		)
		(fp_line
			(start -0.12065 -0.2794)
			(end -0.12065 -0.3048)
			(stroke
				(width 0.1)
				(type default)
			)
			(layer "B.Fab")
		)
		(fp_line
			(start -0.12065 -0.3048)
			(end -0.67945 -0.3048)
			(stroke
				(width 0.1)
				(type default)
			)
			(layer "B.Fab")
		)
		(fp_line
			(start -0.67945 0.3048)
			(end -0.120396 0.3048)
			(stroke
				(width 0.1)
				(type default)
			)
			(layer "B.Fab")
		)
		(fp_line
			(start -0.67945 -0.3048)
			(end -0.67945 0.3048)
			(stroke
				(width 0.1)
				(type default)
			)
			(layer "B.Fab")
		)
		(pad "1" smd circle
			(at 0.40005 0)
			(size 0 0)
			(layers "B.Cu" "B.Mask" "B.Paste")
			(net "RST_CPU0_BUF_R_N")
		)
		(pad "2" smd circle
			(at -0.40005 0)
			(size 0 0)
			(layers "B.Cu" "B.Mask" "B.Paste")
			(net "RST_CPU0_LVC1_N")
		)
	)
)
